(kicad_pcb
	(version 20241229)
	(generator "pcbnew")
	(generator_version "9.0")
	(general
		(thickness 1.711)
		(legacy_teardrops no)
	)
	(paper "A4")
	(title_block
		(title "Antmicro Baseboard for Jetson AGX Thor")
		(date "2026-02-18")
		(rev "1.1.0")
		(company "Antmicro Ltd")
		(comment 1 "www.antmicro.com")
		(comment 9 "footprints 879-882 of 1170")
	)
	(layers
		(0 "F.Cu" signal)
		(4 "In1.Cu" signal)
		(6 "In2.Cu" signal)
		(8 "In3.Cu" signal)
		(10 "In4.Cu" jumper)
		(12 "In5.Cu" signal)
		(14 "In6.Cu" signal)
		(16 "In7.Cu" signal)
		(18 "In8.Cu" signal)
		(2 "B.Cu" signal)
		(9 "F.Adhes" user "F.Adhesive")
		(11 "B.Adhes" user "B.Adhesive")
		(13 "F.Paste" user)
		(15 "B.Paste" user)
		(5 "F.SilkS" user "F.Silkscreen")
		(7 "B.SilkS" user "B.Silkscreen")
		(1 "F.Mask" user)
		(3 "B.Mask" user)
		(17 "Dwgs.User" user "User.Drawings")
		(19 "Cmts.User" user "User.Comments")
		(21 "Eco1.User" user "User.Eco1")
		(23 "Eco2.User" user "User.Eco2")
		(25 "Edge.Cuts" user)
		(27 "Margin" user)
		(31 "F.CrtYd" user "F.Courtyard")
		(29 "B.CrtYd" user "B.Courtyard")
		(35 "F.Fab" user)
		(33 "B.Fab" user)
	)
	(footprint "antmicro-footprints:TP_SMD_0.75mm"
		(layer "B.Cu")
		(at 218.2 100.3 -90)
		(property "Reference" "TP46"
			(at 0.23 -3.131 0)
			(layer "B.SilkS")
			(effects
				(font
					(size 0.7 0.7)
					(thickness 0.15)
				)
				(justify left bottom mirror)
			)
		)
		(property "Value" "TP_0.75mm_SMD"
			(at 0 -1.2 90)
			(layer "B.Fab")
			(effects
				(font
					(size 0.7 0.7)
					(thickness 0.15)
				)
				(justify left bottom mirror)
			)
		)
		(property "Description" "SMT test point"
			(at 0 0 90)
			(layer "B.Fab")
			(hide yes)
			(effects
				(font
					(size 1.27 1.27)
					(thickness 0.15)
				)
				(justify mirror)
			)
		)
		(property "MPN" ""
			(at 0 0 90)
			(unlocked yes)
			(layer "B.Fab")
			(hide yes)
			(effects
				(font
					(size 1 1)
					(thickness 0.15)
				)
				(justify mirror)
			)
		)
		(property "Manufacturer" ""
			(at 0 0 90)
			(unlocked yes)
			(layer "B.Fab")
			(hide yes)
			(effects
				(font
					(size 1 1)
					(thickness 0.15)
				)
				(justify mirror)
			)
		)
		(property "Author" "Antmicro"
			(at 0 0 90)
			(unlocked yes)
			(layer "B.Fab")
			(hide yes)
			(effects
				(font
					(size 1 1)
					(thickness 0.15)
				)
				(justify mirror)
			)
		)
		(property "License" "Apache-2.0"
			(at 0 0 90)
			(unlocked yes)
			(layer "B.Fab")
			(hide yes)
			(effects
				(font
					(size 1 1)
					(thickness 0.15)
				)
				(justify mirror)
			)
		)
		(sheetname "/Recovery USB/")
		(sheetfile "recovery_usb.kicad_sch")
		(attr exclude_from_pos_files exclude_from_bom)
		(fp_circle
			(center 0 0)
			(end 0.475 0)
			(stroke
				(width 0.05)
				(type default)
			)
			(fill no)
			(layer "B.CrtYd")
		)
		(fp_text user "${REFERENCE}"
			(at -0.4 -2.7 90)
			(layer "B.Fab")
			(effects
				(font
					(size 0.7 0.7)
					(thickness 0.15)
				)
				(justify left bottom mirror)
			)
		)
		(fp_text user "Author: Antmicro"
			(at -0.4 -3.901 90)
			(layer "B.Fab")
			(effects
				(font
					(size 0.7 0.7)
					(thickness 0.15)
				)
				(justify left bottom mirror)
			)
		)
		(fp_text user "License: Apache-2.0"
			(at -0.4 -5.101 90)
			(layer "B.Fab")
			(effects
				(font
					(size 0.7 0.7)
					(thickness 0.15)
				)
				(justify left bottom mirror)
			)
		)
		(pad "1" smd circle
			(at 0 0 270)
			(size 0.75 0.75)
			(layers "B.Cu" "B.Mask")
			(net 1014 "/Recovery USB/USBC2_FAULT_N")
			(pinfunction "1")
			(pintype "passive")
		)
	)
	(footprint "antmicro-footprints:C_0805_2012Metric"
		(layer "B.Cu")
		(at 229.1 108.3 90)
		(descr "Capacitor SMD 0805")
		(tags "capacitor SMD 0805")
		(property "Reference" "C115"
			(at -4.5 0.7 90)
			(layer "B.SilkS")
			(effects
				(font
					(size 0.7 0.7)
					(thickness 0.15)
				)
				(justify right top mirror)
			)
		)
		(property "Value" "C_22u_25V_0805"
			(at -2.055717 -1.963153 90)
			(layer "B.Fab")
			(effects
				(font
					(size 0.7 0.7)
					(thickness 0.15)
				)
				(justify right top mirror)
			)
		)
		(property "Datasheet" "https://product.samsungsem.com/mlcc/CL21A226MAYNNN.do"
			(at 0 0 90)
			(layer "B.Fab")
			(hide yes)
			(effects
				(font
					(size 1.27 1.27)
					(thickness 0.15)
				)
				(justify mirror)
			)
		)
		(property "Description" "SMT Multilayer Ceramic Capacitor, 22uF, +/-20%, 25V, X5R, 0805 [2012 Metric]"
			(at 0 0 90)
			(layer "B.Fab")
			(hide yes)
			(effects
				(font
					(size 1.27 1.27)
					(thickness 0.15)
				)
				(justify mirror)
			)
		)
		(property "Manufacturer" "Samsung Electro-Mechanics"
			(at 0 0 90)
			(unlocked yes)
			(layer "B.Fab")
			(hide yes)
			(effects
				(font
					(size 1 1)
					(thickness 0.15)
				)
				(justify mirror)
			)
		)
		(property "MPN" "CL21A226MAYNNNE"
			(at 0 0 90)
			(unlocked yes)
			(layer "B.Fab")
			(hide yes)
			(effects
				(font
					(size 1 1)
					(thickness 0.15)
				)
				(justify mirror)
			)
		)
		(property "Val" "22u"
			(at 0 0 90)
			(unlocked yes)
			(layer "B.Fab")
			(hide yes)
			(effects
				(font
					(size 1 1)
					(thickness 0.15)
				)
				(justify mirror)
			)
		)
		(property "License" "Apache-2.0"
			(at 0 0 90)
			(unlocked yes)
			(layer "B.Fab")
			(hide yes)
			(effects
				(font
					(size 1 1)
					(thickness 0.15)
				)
				(justify mirror)
			)
		)
		(property "Author" "Antmicro"
			(at 0 0 90)
			(unlocked yes)
			(layer "B.Fab")
			(hide yes)
			(effects
				(font
					(size 1 1)
					(thickness 0.15)
				)
				(justify mirror)
			)
		)
		(property "Voltage" "25V"
			(at 0 0 90)
			(unlocked yes)
			(layer "B.Fab")
			(hide yes)
			(effects
				(font
					(size 1 1)
					(thickness 0.15)
				)
				(justify mirror)
			)
		)
		(property "Dielectric" "X5R"
			(at 0 0 90)
			(unlocked yes)
			(layer "B.Fab")
			(hide yes)
			(effects
				(font
					(size 1 1)
					(thickness 0.15)
				)
				(justify mirror)
			)
		)
		(property "Public" "False"
			(at 0 0 90)
			(unlocked yes)
			(layer "B.Fab")
			(hide yes)
			(effects
				(font
					(size 1 1)
					(thickness 0.15)
				)
				(justify mirror)
			)
		)
		(sheetname "/Recovery USB/")
		(sheetfile "recovery_usb.kicad_sch")
		(attr smd)
		(fp_line
			(start -0.3 -0.7)
			(end 0.3 -0.7)
			(stroke
				(width 0.15)
				(type solid)
			)
			(layer "B.SilkS")
		)
		(fp_line
			(start -0.3 0.7)
			(end 0.3 0.7)
			(stroke
				(width 0.15)
				(type solid)
			)
			(layer "B.SilkS")
		)
		(fp_poly
			(pts
				(xy 1.95 0.9) (xy -1.95 0.9) (xy -1.95 -0.9) (xy 1.95 -0.9)
			)
			(stroke
				(width 0.05)
				(type default)
			)
			(fill no)
			(layer "B.CrtYd")
		)
		(fp_poly
			(pts
				(xy -0.95 0.675001) (xy 0.95 0.675001) (xy 0.95 -0.675001) (xy -0.95 -0.675001)
			)
			(stroke
				(width 0.15)
				(type solid)
			)
			(fill no)
			(layer "B.Fab")
		)
		(fp_text user "${REFERENCE}"
			(at -1.899999 -3.947 90)
			(layer "B.Fab")
			(effects
				(font
					(size 0.7 0.7)
					(thickness 0.15)
				)
				(justify right top mirror)
			)
		)
		(fp_text user "Author: Antmicro"
			(at -1.9 -5.947 90)
			(layer "B.Fab")
			(effects
				(font
					(size 0.7 0.7)
					(thickness 0.15)
				)
				(justify right top mirror)
			)
		)
		(fp_text user "License: Apache-2.0"
			(at -1.9 -4.947 90)
			(layer "B.Fab")
			(effects
				(font
					(size 0.7 0.7)
					(thickness 0.15)
				)
				(justify right top mirror)
			)
		)
		(pad "1" smd roundrect
			(at -1.099999 0 90)
			(size 1.2 1.3)
			(layers "B.Cu" "B.Mask" "B.Paste")
			(roundrect_rratio 0.25)
			(net 287 "/Recovery USB/USBC2_VBUS")
			(pintype "passive")
		)
		(pad "2" smd roundrect
			(at 1.099999 0 90)
			(size 1.2 1.3)
			(layers "B.Cu" "B.Mask" "B.Paste")
			(roundrect_rratio 0.25)
			(net 1 "GND")
			(pintype "passive")
		)
	)
	(footprint "antmicro-footprints:LED_0603_1608Metric_G"
		(layer "B.Cu")
		(at 235.425 65.175 180)
		(descr "LED SMD 0603 Green")
		(tags "LED SMD 0603 Green")
		(property "Reference" "D65"
			(at 4.025 -0.025 0)
			(layer "B.SilkS")
			(effects
				(font
					(size 0.7 0.7)
					(thickness 0.15)
				)
				(justify left bottom mirror)
			)
		)
		(property "Value" "LED_G_0603_LTST-C190GKT"
			(at -0.001 -1.599 0)
			(layer "B.Fab")
			(effects
				(font
					(size 0.7 0.7)
					(thickness 0.15)
				)
				(justify left bottom mirror)
			)
		)
		(property "Datasheet" "https://media.digikey.com/pdf/Data%20Sheets/Lite-On%20PDFs/LTST-C190GKT.pdf"
			(at 0 0 0)
			(layer "B.Fab")
			(hide yes)
			(effects
				(font
					(size 1.27 1.27)
					(thickness 0.15)
				)
				(justify mirror)
			)
		)
		(property "Description" "LED, Green, SMD, 0603, 20 mA, 2.1 V, 569 nm"
			(at 0 0 0)
			(layer "B.Fab")
			(hide yes)
			(effects
				(font
					(size 1.27 1.27)
					(thickness 0.15)
				)
				(justify mirror)
			)
		)
		(property "MPN" "LTST-C190GKT"
			(at 0 0 0)
			(unlocked yes)
			(layer "B.Fab")
			(hide yes)
			(effects
				(font
					(size 1 1)
					(thickness 0.15)
				)
				(justify mirror)
			)
		)
		(property "Manufacturer" "Lite-On"
			(at 0 0 0)
			(unlocked yes)
			(layer "B.Fab")
			(hide yes)
			(effects
				(font
					(size 1 1)
					(thickness 0.15)
				)
				(justify mirror)
			)
		)
		(property "Author" "Antmicro"
			(at 0 0 0)
			(unlocked yes)
			(layer "B.Fab")
			(hide yes)
			(effects
				(font
					(size 1 1)
					(thickness 0.15)
				)
				(justify mirror)
			)
		)
		(property "License" "Apache-2.0"
			(at 0 0 0)
			(unlocked yes)
			(layer "B.Fab")
			(hide yes)
			(effects
				(font
					(size 1 1)
					(thickness 0.15)
				)
				(justify mirror)
			)
		)
		(property "Color" "Green"
			(at 0 0 0)
			(unlocked yes)
			(layer "B.Fab")
			(hide yes)
			(effects
				(font
					(size 1 1)
					(thickness 0.15)
				)
				(justify mirror)
			)
		)
		(sheetname "/SoM_Power/")
		(sheetfile "som_power.kicad_sch")
		(attr smd)
		(fp_line
			(start 0.22 0.35)
			(end -0.22 0.35)
			(stroke
				(width 0.15)
				(type solid)
			)
			(layer "B.SilkS")
		)
		(fp_line
			(start 0.22 -0.35)
			(end -0.22 -0.35)
			(stroke
				(width 0.15)
				(type solid)
			)
			(layer "B.SilkS")
		)
		(fp_line
			(start 0.105328 -0.001008)
			(end 0.240001 -0.001)
			(stroke
				(width 0.1)
				(type solid)
			)
			(layer "B.SilkS")
		)
		(fp_line
			(start 0.105328 -0.201008)
			(end 0.105329 0.198992)
			(stroke
				(width 0.1)
				(type solid)
			)
			(layer "B.SilkS")
		)
		(fp_line
			(start 0.105328 -0.201008)
			(end -0.094672 -0.001008)
			(stroke
				(width 0.1)
				(type solid)
			)
			(layer "B.SilkS")
		)
		(fp_line
			(start -0.094672 -0.001008)
			(end 0.105329 0.198992)
			(stroke
				(width 0.1)
				(type solid)
			)
			(layer "B.SilkS")
		)
		(fp_line
			(start -0.094672 -0.001008)
			(end -0.24 -0.001008)
			(stroke
				(width 0.1)
				(type solid)
			)
			(layer "B.SilkS")
		)
		(fp_line
			(start -0.094672 -0.201008)
			(end -0.094672 0.198992)
			(stroke
				(width 0.1)
				(type solid)
			)
			(layer "B.SilkS")
		)
		(fp_line
			(start -1.18 0.319)
			(end -1.18 -0.321)
			(stroke
				(width 0.15)
				(type solid)
			)
			(layer "B.SilkS")
		)
		(fp_poly
			(pts
				(xy 1.25 -0.65) (xy -1.25 -0.65) (xy -1.25 0.65) (xy 1.25 0.65)
			)
			(stroke
				(width 0.05)
				(type solid)
			)
			(fill no)
			(layer "B.CrtYd")
		)
		(fp_line
			(start 0.599 0)
			(end 0.200999 0)
			(stroke
				(width 0.15)
				(type solid)
			)
			(layer "B.Fab")
		)
		(fp_line
			(start 0.201 0.202)
			(end -0.101 0)
			(stroke
				(width 0.15)
				(type solid)
			)
			(layer "B.Fab")
		)
		(fp_line
			(start 0.201 -0.2)
			(end 0.200999 0)
			(stroke
				(width 0.15)
				(type solid)
			)
			(layer "B.Fab")
		)
		(fp_line
			(start 0.200999 0)
			(end 0.201 0.202)
			(stroke
				(width 0.15)
				(type solid)
			)
			(layer "B.Fab")
		)
		(fp_line
			(start -0.101 0)
			(end 0.201 -0.2)
			(stroke
				(width 0.15)
				(type solid)
			)
			(layer "B.Fab")
		)
		(fp_line
			(start -0.199 0.202)
			(end -0.199 -0.1)
			(stroke
				(width 0.15)
				(type solid)
			)
			(layer "B.Fab")
		)
		(fp_line
			(start -0.199 0)
			(end -0.597 0)
			(stroke
				(width 0.15)
				(type solid)
			)
			(layer "B.Fab")
		)
		(fp_line
			(start -0.199 -0.2)
			(end -0.199 -0.1)
			(stroke
				(width 0.15)
				(type solid)
			)
			(layer "B.Fab")
		)
		(fp_poly
			(pts
				(xy 0.848 -0.4) (xy -0.85 -0.4) (xy -0.85 0.402) (xy 0.848 0.401999)
			)
			(stroke
				(width 0.15)
				(type solid)
			)
			(fill no)
			(layer "B.Fab")
		)
		(fp_text user "Author: Antmicro"
			(at -1.4224 -4.799 0)
			(layer "B.Fab")
			(effects
				(font
					(size 0.7 0.7)
					(thickness 0.15)
				)
				(justify left bottom mirror)
			)
		)
		(fp_text user "${REFERENCE}"
			(at -1.4224 -5.999 0)
			(layer "B.Fab")
			(effects
				(font
					(size 0.7 0.7)
					(thickness 0.15)
				)
				(justify left bottom mirror)
			)
		)
		(fp_text user "License: Apache-2.0"
			(at -1.4224 -3.599 0)
			(layer "B.Fab")
			(effects
				(font
					(size 0.7 0.7)
					(thickness 0.15)
				)
				(justify left bottom mirror)
			)
		)
		(pad "1" smd roundrect
			(at -0.7 0)
			(size 0.8 1)
			(layers "B.Cu" "B.Mask" "B.Paste")
			(roundrect_rratio 0.2)
			(net 1393 "Net-(D65-C)")
			(pinfunction "C")
			(pintype "passive")
		)
		(pad "2" smd roundrect
			(at 0.7 0)
			(size 0.8 1)
			(layers "B.Cu" "B.Mask" "B.Paste")
			(roundrect_rratio 0.2)
			(net 1394 "Net-(D65-A)")
			(pinfunction "A")
			(pintype "passive")
		)
	)
	(footprint "antmicro-footprints:TP_SMD_0.75mm"
		(layer "B.Cu")
		(at 200.2 116.4 90)
		(property "Reference" "TP65"
			(at 0.58 -0.33 90)
			(layer "B.SilkS")
			(effects
				(font
					(size 0.7 0.7)
					(thickness 0.15)
				)
				(justify right top mirror)
			)
		)
		(property "Value" "TP_0.75mm_SMD"
			(at 0 -1.2 90)
			(layer "B.Fab")
			(effects
				(font
					(size 0.7 0.7)
					(thickness 0.15)
				)
				(justify right top mirror)
			)
		)
		(property "Description" "SMT test point"
			(at 0 0 90)
			(layer "B.Fab")
			(hide yes)
			(effects
				(font
					(size 1.27 1.27)
					(thickness 0.15)
				)
				(justify mirror)
			)
		)
		(property "MPN" ""
			(at 0 0 270)
			(unlocked yes)
			(layer "B.Fab")
			(hide yes)
			(effects
				(font
					(size 1 1)
					(thickness 0.15)
				)
				(justify mirror)
			)
		)
		(property "Manufacturer" ""
			(at 0 0 270)
			(unlocked yes)
			(layer "B.Fab")
			(hide yes)
			(effects
				(font
					(size 1 1)
					(thickness 0.15)
				)
				(justify mirror)
			)
		)
		(property "Author" "Antmicro"
			(at 0 0 270)
			(unlocked yes)
			(layer "B.Fab")
			(hide yes)
			(effects
				(font
					(size 1 1)
					(thickness 0.15)
				)
				(justify mirror)
			)
		)
		(property "License" "Apache-2.0"
			(at 0 0 270)
			(unlocked yes)
			(layer "B.Fab")
			(hide yes)
			(effects
				(font
					(size 1 1)
					(thickness 0.15)
				)
				(justify mirror)
			)
		)
		(sheetname "/USB Hub/")
		(sheetfile "usb_hub.kicad_sch")
		(attr exclude_from_pos_files exclude_from_bom)
		(fp_circle
			(center 0 0)
			(end 0.475 0)
			(stroke
				(width 0.05)
				(type default)
			)
			(fill no)
			(layer "B.CrtYd")
		)
		(fp_text user "${REFERENCE}"
			(at -0.4 -2.7 90)
			(layer "B.Fab")
			(effects
				(font
					(size 0.7 0.7)
					(thickness 0.15)
				)
				(justify right top mirror)
			)
		)
		(fp_text user "Author: Antmicro"
			(at -0.4 -3.901 90)
			(layer "B.Fab")
			(effects
				(font
					(size 0.7 0.7)
					(thickness 0.15)
				)
				(justify right top mirror)
			)
		)
		(fp_text user "License: Apache-2.0"
			(at -0.4 -5.101 90)
			(layer "B.Fab")
			(effects
				(font
					(size 0.7 0.7)
					(thickness 0.15)
				)
				(justify right top mirror)
			)
		)
		(pad "1" smd circle
			(at 0 0 90)
			(size 0.75 0.75)
			(layers "B.Cu" "B.Mask")
			(net 1085 "/USB Hub/DP2_DISCH")
			(pinfunction "1")
			(pintype "passive")
		)
	)
)
